(kicad_pcb
	(version 20260206)
	(generator "pcbnew")
	(generator_version "10.0")
	(general
		(thickness 1.6)
		(legacy_teardrops no)
	)
	(paper "A4")
	(title_block
		(title "Bryce Canyon_SCC_16316-1_OCP.brd")
		(comment 1 "Bryce Canyon / footprints 311-317 of 1561")
	)
	(layers
		(0 "F.Cu" signal "TOP")
		(4 "In1.Cu" signal "L2GND")
		(6 "In2.Cu" signal "L3")
		(8 "In3.Cu" signal "L4VCC")
		(10 "In4.Cu" signal "L5VCC")
		(12 "In5.Cu" signal "L6")
		(14 "In6.Cu" signal "L7GND")
		(2 "B.Cu" signal "BOTTOM")
		(9 "F.Adhes" user "F.Adhesive")
		(11 "B.Adhes" user "B.Adhesive")
		(13 "F.Paste" user "Package Geometry/Pastemask Top")
		(15 "B.Paste" user "Package Geometry/Pastemask Bottom")
		(5 "F.SilkS" user "Ref Des/Silkscreen Top")
		(7 "B.SilkS" user "Ref Des/Silkscreen Bottom")
		(1 "F.Mask" user "Board Geometry/Soldermask Top")
		(3 "B.Mask" user "Board Geometry/Soldermask Bottom")
		(17 "Dwgs.User" user "User.Drawings")
		(19 "Cmts.User" user "User.Comments")
		(21 "Eco1.User" user "User.Eco1")
		(23 "Eco2.User" user "User.Eco2")
		(25 "Edge.Cuts" user "Board Geometry/Outline")
		(27 "Margin" user)
		(31 "F.CrtYd" user "Package Geometry/Place Bound Top")
		(29 "B.CrtYd" user "Package Geometry/Place Bound Bottom")
		(35 "F.Fab" user "Ref Des/Assembly Top")
		(33 "B.Fab" user "Ref Des/Assembly Bottom")
	)
	(footprint ""
		(layer "F.Cu")
		(at 62.9666 -37.465 -90)
		(property "Reference" "TC3"
			(at 0 0 270)
			(layer "F.SilkS")
			(hide yes)
			(effects
				(font
					(size 1.27 1.27)
				)
			)
		)
		(property "Value" "SE470UF2VDM-GP"
			(at 0 -9.6012 270)
			(unlocked yes)
			(layer "F.Fab")
			(hide yes)
			(effects
				(font
					(size 1.016 1.016)
					(thickness 0.1524)
				)
			)
		)
		(property "Device Type" "CT7343H83"
			(at 0 -11.1252 270)
			(unlocked yes)
			(layer "F.Fab")
			(hide yes)
			(effects
				(font
					(size 1.016 1.016)
					(thickness 0.1524)
				)
			)
		)
		(duplicate_pad_numbers_are_jumpers no)
		(fp_line
			(start -2.286 4.8768)
			(end -2.286 2.032)
			(stroke
				(width 0.1524)
				(type default)
			)
			(layer "F.SilkS")
		)
		(fp_line
			(start 2.286 4.8768)
			(end -2.286 4.8768)
			(stroke
				(width 0.1524)
				(type default)
			)
			(layer "F.SilkS")
		)
		(fp_line
			(start 2.286 2.032)
			(end 2.286 4.8768)
			(stroke
				(width 0.1524)
				(type default)
			)
			(layer "F.SilkS")
		)
		(fp_line
			(start 2.286 -2.032)
			(end 2.286 -4.8768)
			(stroke
				(width 0.1524)
				(type default)
			)
			(layer "F.SilkS")
		)
		(fp_line
			(start 2.1082 -4.699)
			(end -2.1082 -4.699)
			(stroke
				(width 0.508)
				(type default)
			)
			(layer "F.SilkS")
		)
		(fp_line
			(start -2.286 -4.8768)
			(end -2.286 -2.032)
			(stroke
				(width 0.1524)
				(type default)
			)
			(layer "F.SilkS")
		)
		(fp_line
			(start 2.286 -4.8768)
			(end -2.286 -4.8768)
			(stroke
				(width 0.1524)
				(type default)
			)
			(layer "F.SilkS")
		)
		(fp_rect
			(start -2.1463 3.6449)
			(end 2.1463 -3.6449)
			(stroke
				(width 0)
				(type default)
			)
			(fill no)
			(layer "F.CrtYd")
		)
		(fp_poly
			(pts
				(xy -2.54 4.953) (xy -2.54 4.2926) (xy -3.81 4.2926) (xy -3.81 -4.2926) (xy -2.54 -4.2926) (xy -2.54 -4.953)
				(xy 2.54 -4.953) (xy 2.54 -4.2926) (xy 3.81 -4.2926) (xy 3.81 -1.6256) (xy 2.1463 -1.6256) (xy 2.1463 -3.6449)
				(xy -2.1463 -3.6449) (xy -2.1463 3.6449) (xy 2.1463 3.6449) (xy 2.1463 -1.6129) (xy 3.81 -1.6129)
				(xy 3.81 4.2926) (xy 2.54 4.2926) (xy 2.54 4.953)
			)
			(stroke
				(width 0)
				(type default)
			)
			(fill no)
			(layer "F.CrtYd")
		)
		(fp_rect
			(start -2.54 4.953)
			(end 2.54 -4.953)
			(stroke
				(width 0)
				(type default)
			)
			(fill no)
			(layer "F.Fab")
		)
		(fp_rect
			(start -3.81 4.2926)
			(end -2.54 -4.2926)
			(stroke
				(width 0)
				(type default)
			)
			(fill no)
			(layer "F.Fab")
		)
		(fp_rect
			(start 2.54 4.2926)
			(end 3.81 -4.2926)
			(stroke
				(width 0)
				(type default)
			)
			(fill no)
			(layer "F.Fab")
		)
		(pad "1" smd rect
			(at 0 -3.1496 270)
			(size 2.413 2.286)
			(layers "F.Cu" "F.Mask" "F.Paste")
			(net "P0V9")
		)
		(pad "2" smd rect
			(at 0 3.1496 270)
			(size 2.413 2.286)
			(layers "F.Cu" "F.Mask" "F.Paste")
			(net "GND")
		)
		(zone
			(layer "F.Cu")
			(hatch none 0.5)
			(connect_pads
				(clearance 0)
			)
			(min_thickness 0.25)
			(keepout
				(tracks allowed)
				(vias not_allowed)
				(pads allowed)
				(copperpour not_allowed)
				(footprints allowed)
			)
			(placement
				(enabled no)
				(sheetname "")
			)
			(fill
				(thermal_gap 0.5)
				(thermal_bridge_width 0.5)
				(island_removal_mode 0)
			)
			(polygon
				(pts
					(xy 58.3692 -38.9763) (xy 58.3692 -35.9537) (xy 61.2648 -35.9537) (xy 61.595 -35.9537) (xy 61.595 -38.9763)
					(xy 61.2648 -38.9763)
				)
			)
		)
		(zone
			(layer "F.Cu")
			(hatch none 0.5)
			(connect_pads
				(clearance 0)
			)
			(min_thickness 0.25)
			(keepout
				(tracks allowed)
				(vias not_allowed)
				(pads allowed)
				(copperpour not_allowed)
				(footprints allowed)
			)
			(placement
				(enabled no)
				(sheetname "")
			)
			(fill
				(thermal_gap 0.5)
				(thermal_bridge_width 0.5)
				(island_removal_mode 0)
			)
			(polygon
				(pts
					(xy 64.6557 -35.9537) (xy 67.564 -35.9537) (xy 67.564 -38.9763) (xy 64.6684 -38.9763) (xy 64.3382 -38.9763)
					(xy 64.3382 -35.9537)
				)
			)
		)
	)
	(footprint ""
		(layer "F.Cu")
		(at 175.387 -97.4852 180)
		(property "Reference" "C661"
			(at 0 0 180)
			(layer "F.SilkS")
			(hide yes)
			(effects
				(font
					(size 1.27 1.27)
				)
			)
		)
		(property "Value" "SC6K8P50V2KX-GP"
			(at 1.1811 -2.7051 180)
			(unlocked yes)
			(layer "F.Fab")
			(hide yes)
			(effects
				(font
					(size 1.016 1.016)
					(thickness 0.1524)
				)
			)
		)
		(property "Device Type" "C402H22"
			(at 1.1811 -4.2291 180)
			(unlocked yes)
			(layer "F.Fab")
			(hide yes)
			(effects
				(font
					(size 1.016 1.016)
					(thickness 0.1524)
				)
			)
		)
		(duplicate_pad_numbers_are_jumpers no)
		(fp_rect
			(start -0.4318 0.9525)
			(end 0.4318 -0.9525)
			(stroke
				(width 0)
				(type default)
			)
			(fill no)
			(layer "F.CrtYd")
		)
		(fp_rect
			(start -0.4318 0.9525)
			(end 0.4318 -0.9525)
			(stroke
				(width 0)
				(type default)
			)
			(fill no)
			(layer "F.Fab")
		)
		(pad "1" smd custom
			(at 0 -0.4445 180)
			(size 0.1524 0.1524)
			(layers "F.Cu" "F.Mask" "F.Paste")
			(net "VT235_VFB")
			(options
				(clearance outline)
				(anchor circle)
			)
			(primitives
				(gr_poly
					(pts
						(arc
							(start 0.3048 -0.2032)
							(mid 0.275042 -0.275042)
							(end 0.2032 -0.3048)
						)
						(arc
							(start -0.2032 -0.3048)
							(mid -0.275042 -0.275042)
							(end -0.3048 -0.2032)
						)
						(arc
							(start -0.3048 0.2032)
							(mid -0.275042 0.275042)
							(end -0.2032 0.3048)
						)
						(arc
							(start 0.2032 0.3048)
							(mid 0.275042 0.275042)
							(end 0.3048 0.2032)
						)
					)
					(width 0)
					(fill yes)
				)
			)
		)
		(pad "2" smd custom
			(at 0 0.4445 180)
			(size 0.1524 0.1524)
			(layers "F.Cu" "F.Mask" "F.Paste")
			(net "VT235_VDES")
			(options
				(clearance outline)
				(anchor circle)
			)
			(primitives
				(gr_poly
					(pts
						(arc
							(start 0.3048 -0.2032)
							(mid 0.275042 -0.275042)
							(end 0.2032 -0.3048)
						)
						(arc
							(start -0.2032 -0.3048)
							(mid -0.275042 -0.275042)
							(end -0.3048 -0.2032)
						)
						(arc
							(start -0.3048 0.2032)
							(mid -0.275042 0.275042)
							(end -0.2032 0.3048)
						)
						(arc
							(start 0.2032 0.3048)
							(mid 0.275042 0.275042)
							(end 0.3048 0.2032)
						)
					)
					(width 0)
					(fill yes)
				)
			)
		)
	)
	(footprint ""
		(layer "F.Cu")
		(at 87.602314 -52.79136)
		(property "Reference" "C111"
			(at 0 0 0)
			(layer "F.SilkS")
			(hide yes)
			(effects
				(font
					(size 1.27 1.27)
				)
			)
		)
		(property "Value" "SC15P50V2JN-2-GP"
			(at 1.1811 -2.7051 0)
			(unlocked yes)
			(layer "F.Fab")
			(hide yes)
			(effects
				(font
					(size 1.016 1.016)
					(thickness 0.1524)
				)
			)
		)
		(property "Device Type" "C402H22"
			(at 1.1811 -4.2291 0)
			(unlocked yes)
			(layer "F.Fab")
			(hide yes)
			(effects
				(font
					(size 1.016 1.016)
					(thickness 0.1524)
				)
			)
		)
		(duplicate_pad_numbers_are_jumpers no)
		(fp_rect
			(start -0.4318 0.9525)
			(end 0.4318 -0.9525)
			(stroke
				(width 0)
				(type default)
			)
			(fill no)
			(layer "F.CrtYd")
		)
		(fp_rect
			(start -0.4318 0.9525)
			(end 0.4318 -0.9525)
			(stroke
				(width 0)
				(type default)
			)
			(fill no)
			(layer "F.Fab")
		)
		(pad "1" smd custom
			(at 0 -0.4445)
			(size 0.1524 0.1524)
			(layers "F.Cu" "F.Mask" "F.Paste")
			(net "EXP_REF_CLK_R_N")
			(options
				(clearance outline)
				(anchor circle)
			)
			(primitives
				(gr_poly
					(pts
						(arc
							(start 0.3048 -0.2032)
							(mid 0.275042 -0.275042)
							(end 0.2032 -0.3048)
						)
						(arc
							(start -0.2032 -0.3048)
							(mid -0.275042 -0.275042)
							(end -0.3048 -0.2032)
						)
						(arc
							(start -0.3048 0.2032)
							(mid -0.275042 0.275042)
							(end -0.2032 0.3048)
						)
						(arc
							(start 0.2032 0.3048)
							(mid 0.275042 0.275042)
							(end 0.3048 0.2032)
						)
					)
					(width 0)
					(fill yes)
				)
			)
		)
		(pad "2" smd custom
			(at 0 0.4445)
			(size 0.1524 0.1524)
			(layers "F.Cu" "F.Mask" "F.Paste")
			(net "GND")
			(options
				(clearance outline)
				(anchor circle)
			)
			(primitives
				(gr_poly
					(pts
						(arc
							(start 0.3048 -0.2032)
							(mid 0.275042 -0.275042)
							(end 0.2032 -0.3048)
						)
						(arc
							(start -0.2032 -0.3048)
							(mid -0.275042 -0.275042)
							(end -0.3048 -0.2032)
						)
						(arc
							(start -0.3048 0.2032)
							(mid -0.275042 0.275042)
							(end -0.2032 0.3048)
						)
						(arc
							(start 0.2032 0.3048)
							(mid 0.275042 0.275042)
							(end 0.3048 0.2032)
						)
					)
					(width 0)
					(fill yes)
				)
			)
		)
	)
	(footprint ""
		(layer "F.Cu")
		(at 151.113236 -38.55212 -78)
		(property "Reference" "VIA19"
			(at 0 0 282)
			(layer "F.SilkS")
			(hide yes)
			(effects
				(font
					(size 1.27 1.27)
				)
			)
		)
		(property "Value" "100OHM-8L-1D6MM-L13-GP"
			(at 3.289333 0.050849 282)
			(unlocked yes)
			(layer "F.Fab")
			(hide yes)
			(effects
				(font
					(size 1.016 1.016)
					(thickness 0.1524)
				)
			)
		)
		(property "Device Type" "VIA-PCIE-4P-409091"
			(at 3.289207 -1.473208 282)
			(unlocked yes)
			(layer "F.Fab")
			(hide yes)
			(effects
				(font
					(size 1.016 1.016)
					(thickness 0.1524)
				)
			)
		)
		(duplicate_pad_numbers_are_jumpers no)
		(fp_poly
			(pts
				(xy -2.044719 -0.457296) (xy 2.04468 -0.457296) (xy 2.044681 0.457104) (xy -2.044719 0.457104)
			)
			(stroke
				(width 0)
				(type default)
			)
			(fill no)
			(layer "F.CrtYd")
		)
		(fp_poly
			(pts
				(xy -2.044719 -0.457296) (xy 2.04468 -0.457296) (xy 2.044681 0.457104) (xy -2.044719 0.457104)
			)
			(stroke
				(width 0)
				(type default)
			)
			(fill no)
			(layer "F.Fab")
		)
		(pad "1" thru_hole circle
			(at -1.5875 0 282)
			(size 0.508 0.508)
			(drill 0.254)
			(layers "*.Cu" "*.Mask")
			(remove_unused_layers no)
			(net "GND")
			(clearance 0.2032)
			(thermal_gap 0.2032)
		)
		(pad "2" thru_hole circle
			(at -0.5715 0.000001 282)
			(size 0.508 0.508)
			(drill 0.254)
			(layers "*.Cu" "*.Mask")
			(remove_unused_layers no)
			(net "PHY_SCC_TO_IOC_C_42_DP")
			(clearance 0.2032)
			(thermal_gap 0.2032)
		)
		(pad "3" thru_hole circle
			(at 0.5715 -0.000001 282)
			(size 0.508 0.508)
			(drill 0.254)
			(layers "*.Cu" "*.Mask")
			(remove_unused_layers no)
			(net "PHY_SCC_TO_IOC_C_42_DN")
			(clearance 0.2032)
			(thermal_gap 0.2032)
		)
		(pad "4" thru_hole circle
			(at 1.5875 0 282)
			(size 0.508 0.508)
			(drill 0.254)
			(layers "*.Cu" "*.Mask")
			(remove_unused_layers no)
			(net "GND")
			(clearance 0.2032)
			(thermal_gap 0.2032)
		)
	)
	(footprint ""
		(layer "F.Cu")
		(at 185.9026 -22.9362)
		(property "Reference" "R276"
			(at 0 0 0)
			(layer "F.SilkS")
			(hide yes)
			(effects
				(font
					(size 1.27 1.27)
				)
			)
		)
		(property "Value" "4K7R2F-GP"
			(at 0.064008 -3.993896 0)
			(unlocked yes)
			(layer "F.Fab")
			(hide yes)
			(effects
				(font
					(size 1.016 1.016)
					(thickness 0.1524)
				)
			)
		)
		(property "Device Type" "R402H16"
			(at 0.064008 -5.517896 0)
			(unlocked yes)
			(layer "F.Fab")
			(hide yes)
			(effects
				(font
					(size 1.016 1.016)
					(thickness 0.1524)
				)
			)
		)
		(duplicate_pad_numbers_are_jumpers no)
		(fp_line
			(start -0.508 -0.9398)
			(end -0.508 0.9398)
			(stroke
				(width 0.1524)
				(type default)
			)
			(layer "F.SilkS")
		)
		(fp_line
			(start 0.508 -0.9398)
			(end -0.508 -0.9398)
			(stroke
				(width 0.1524)
				(type default)
			)
			(layer "F.SilkS")
		)
		(fp_rect
			(start -0.508 0.9398)
			(end 0.508 -0.9398)
			(stroke
				(width 0)
				(type default)
			)
			(fill no)
			(layer "F.CrtYd")
		)
		(fp_rect
			(start -0.508 0.9398)
			(end 0.508 -0.9398)
			(stroke
				(width 0)
				(type default)
			)
			(fill no)
			(layer "F.Fab")
		)
		(pad "1" smd custom
			(at 0 -0.4445)
			(size 0.1397 0.1397)
			(layers "F.Cu" "F.Mask" "F.Paste")
			(net "SYS_DBMODE4")
			(options
				(clearance outline)
				(anchor circle)
			)
			(primitives
				(gr_poly
					(pts
						(arc
							(start -0.1778 -0.2794)
							(mid -0.249642 -0.249642)
							(end -0.2794 -0.1778)
						)
						(arc
							(start -0.2794 0.1778)
							(mid -0.249642 0.249642)
							(end -0.1778 0.2794)
						)
						(arc
							(start 0.1778 0.2794)
							(mid 0.249642 0.249642)
							(end 0.2794 0.1778)
						)
						(arc
							(start 0.2794 -0.1778)
							(mid 0.249642 -0.249642)
							(end 0.1778 -0.2794)
						)
					)
					(width 0)
					(fill yes)
				)
			)
		)
		(pad "2" smd custom
			(at 0 0.4445)
			(size 0.1397 0.1397)
			(layers "F.Cu" "F.Mask" "F.Paste")
			(net "GND")
			(options
				(clearance outline)
				(anchor circle)
			)
			(primitives
				(gr_poly
					(pts
						(arc
							(start -0.1778 -0.2794)
							(mid -0.249642 -0.249642)
							(end -0.2794 -0.1778)
						)
						(arc
							(start -0.2794 0.1778)
							(mid -0.249642 0.249642)
							(end -0.1778 0.2794)
						)
						(arc
							(start 0.1778 0.2794)
							(mid 0.249642 0.249642)
							(end 0.2794 0.1778)
						)
						(arc
							(start 0.2794 -0.1778)
							(mid 0.249642 -0.249642)
							(end 0.1778 -0.2794)
						)
					)
					(width 0)
					(fill yes)
				)
			)
		)
	)
	(footprint ""
		(layer "F.Cu")
		(at 157.48 -42.291 -90)
		(property "Reference" "C335"
			(at 0 0 270)
			(layer "F.SilkS")
			(hide yes)
			(effects
				(font
					(size 1.27 1.27)
				)
			)
		)
		(property "Value" "SC15P50V2JN-2-GP"
			(at 1.1811 -2.7051 270)
			(unlocked yes)
			(layer "F.Fab")
			(hide yes)
			(effects
				(font
					(size 1.016 1.016)
					(thickness 0.1524)
				)
			)
		)
		(property "Device Type" "C402H22"
			(at 1.1811 -4.2291 270)
			(unlocked yes)
			(layer "F.Fab")
			(hide yes)
			(effects
				(font
					(size 1.016 1.016)
					(thickness 0.1524)
				)
			)
		)
		(duplicate_pad_numbers_are_jumpers no)
		(fp_rect
			(start -0.4318 0.9525)
			(end 0.4318 -0.9525)
			(stroke
				(width 0)
				(type default)
			)
			(fill no)
			(layer "F.CrtYd")
		)
		(fp_rect
			(start -0.4318 0.9525)
			(end 0.4318 -0.9525)
			(stroke
				(width 0)
				(type default)
			)
			(fill no)
			(layer "F.Fab")
		)
		(pad "1" smd custom
			(at 0 -0.4445 270)
			(size 0.1524 0.1524)
			(layers "F.Cu" "F.Mask" "F.Paste")
			(net "REF_CLK")
			(options
				(clearance outline)
				(anchor circle)
			)
			(primitives
				(gr_poly
					(pts
						(arc
							(start 0.3048 -0.2032)
							(mid 0.275042 -0.275042)
							(end 0.2032 -0.3048)
						)
						(arc
							(start -0.2032 -0.3048)
							(mid -0.275042 -0.275042)
							(end -0.3048 -0.2032)
						)
						(arc
							(start -0.3048 0.2032)
							(mid -0.275042 0.275042)
							(end -0.2032 0.3048)
						)
						(arc
							(start 0.2032 0.3048)
							(mid 0.275042 0.275042)
							(end 0.3048 0.2032)
						)
					)
					(width 0)
					(fill yes)
				)
			)
		)
		(pad "2" smd custom
			(at 0 0.4445 270)
			(size 0.1524 0.1524)
			(layers "F.Cu" "F.Mask" "F.Paste")
			(net "GND")
			(options
				(clearance outline)
				(anchor circle)
			)
			(primitives
				(gr_poly
					(pts
						(arc
							(start 0.3048 -0.2032)
							(mid 0.275042 -0.275042)
							(end 0.2032 -0.3048)
						)
						(arc
							(start -0.2032 -0.3048)
							(mid -0.275042 -0.275042)
							(end -0.3048 -0.2032)
						)
						(arc
							(start -0.3048 0.2032)
							(mid -0.275042 0.275042)
							(end -0.2032 0.3048)
						)
						(arc
							(start 0.2032 0.3048)
							(mid 0.275042 0.275042)
							(end 0.3048 0.2032)
						)
					)
					(width 0)
					(fill yes)
				)
			)
		)
	)
	(footprint ""
		(layer "F.Cu")
		(at 53.213 -72.136 -90)
		(property "Reference" "R470"
			(at 0 0 270)
			(layer "F.SilkS")
			(hide yes)
			(effects
				(font
					(size 1.27 1.27)
				)
			)
		)
		(property "Value" "200KR2F-L-GP"
			(at 0.064008 -3.993896 270)
			(unlocked yes)
			(layer "F.Fab")
			(hide yes)
			(effects
				(font
					(size 1.016 1.016)
					(thickness 0.1524)
				)
			)
		)
		(property "Device Type" "R402H16"
			(at 0.064008 -5.517896 270)
			(unlocked yes)
			(layer "F.Fab")
			(hide yes)
			(effects
				(font
					(size 1.016 1.016)
					(thickness 0.1524)
				)
			)
		)
		(duplicate_pad_numbers_are_jumpers no)
		(fp_line
			(start -0.508 -0.9398)
			(end -0.508 0.9398)
			(stroke
				(width 0.1524)
				(type default)
			)
			(layer "F.SilkS")
		)
		(fp_line
			(start 0.508 -0.9398)
			(end -0.508 -0.9398)
			(stroke
				(width 0.1524)
				(type default)
			)
			(layer "F.SilkS")
		)
		(fp_rect
			(start -0.508 0.9398)
			(end 0.508 -0.9398)
			(stroke
				(width 0)
				(type default)
			)
			(fill no)
			(layer "F.CrtYd")
		)
		(fp_rect
			(start -0.508 0.9398)
			(end 0.508 -0.9398)
			(stroke
				(width 0)
				(type default)
			)
			(fill no)
			(layer "F.Fab")
		)
		(pad "1" smd custom
			(at 0 -0.4445 270)
			(size 0.1397 0.1397)
			(layers "F.Cu" "F.Mask" "F.Paste")
			(net "VREF7")
			(options
				(clearance outline)
				(anchor circle)
			)
			(primitives
				(gr_poly
					(pts
						(arc
							(start -0.1778 -0.2794)
							(mid -0.249642 -0.249642)
							(end -0.2794 -0.1778)
						)
						(arc
							(start -0.2794 0.1778)
							(mid -0.249642 0.249642)
							(end -0.1778 0.2794)
						)
						(arc
							(start 0.1778 0.2794)
							(mid 0.249642 0.249642)
							(end 0.2794 0.1778)
						)
						(arc
							(start 0.2794 -0.1778)
							(mid 0.249642 -0.249642)
							(end 0.1778 -0.2794)
						)
					)
					(width 0)
					(fill yes)
				)
			)
		)
		(pad "2" smd custom
			(at 0 0.4445 270)
			(size 0.1397 0.1397)
			(layers "F.Cu" "F.Mask" "F.Paste")
			(net "P3V3")
			(options
				(clearance outline)
				(anchor circle)
			)
			(primitives
				(gr_poly
					(pts
						(arc
							(start -0.1778 -0.2794)
							(mid -0.249642 -0.249642)
							(end -0.2794 -0.1778)
						)
						(arc
							(start -0.2794 0.1778)
							(mid -0.249642 0.249642)
							(end -0.1778 0.2794)
						)
						(arc
							(start 0.1778 0.2794)
							(mid 0.249642 0.249642)
							(end 0.2794 0.1778)
						)
						(arc
							(start 0.2794 -0.1778)
							(mid 0.249642 -0.249642)
							(end 0.1778 -0.2794)
						)
					)
					(width 0)
					(fill yes)
				)
			)
		)
	)
)
